# TIMECARD (Time Appliance Project (Time Card)) — schematic netlist excerpt (pin names and nets, part order shuffled) for the footprints in the layout excerpt that follows; sources: Cadence DE-HDL packaged netlist, KiCad conversion of R4006-B0001-02_R01.brd

R474  RESISTOR  100KOHM 1%  pkg SMC_0402R_H016  page 24 : \1\ = XP3R3V_FPGA ; \2\ = FPGA_PCA9546_I2C_SDA
TP1  TP_PIONT  pkg TP010CT020B030_PTH  page 20 : \1\ = BNO080_EVN_SDA

(kicad_pcb
	(version 20260206)
	(generator "pcbnew")
	(generator_version "10.0")
	(general
		(thickness 1.6)
		(legacy_teardrops no)
	)
	(paper "A4")
	(title_block
		(title "timecard-production-celestica-r4006 — R4006-B0001-02_R01.brd")
		(comment 1 "Time Appliance Project (Time Card) / footprints 468-469 of 1113")
	)
	(layers
		(0 "F.Cu" signal "TOP")
		(4 "In1.Cu" signal "L02_GND1")
		(6 "In2.Cu" signal "L03_SIG1")
		(8 "In3.Cu" signal "L04_GND2")
		(10 "In4.Cu" signal "L05_VCC1")
		(12 "In5.Cu" signal "L06_VCC2")
		(14 "In6.Cu" signal "L07_GND3")
		(16 "In7.Cu" signal "L08_SIG2")
		(18 "In8.Cu" signal "L09_GND4")
		(2 "B.Cu" signal "BOTTOM")
		(9 "F.Adhes" user "F.Adhesive")
		(11 "B.Adhes" user "B.Adhesive")
		(13 "F.Paste" user "Package Geometry/Pastemask Top")
		(15 "B.Paste" user "Package Geometry/Pastemask Bottom")
		(5 "F.SilkS" user "Ref Des/Silkscreen Top")
		(7 "B.SilkS" user "Ref Des/Silkscreen Bottom")
		(1 "F.Mask" user "Board Geometry/Soldermask Top")
		(3 "B.Mask" user "Board Geometry/Soldermask Bottom")
		(17 "Dwgs.User" user "User.Drawings")
		(19 "Cmts.User" user "User.Comments")
		(21 "Eco1.User" user "User.Eco1")
		(23 "Eco2.User" user "User.Eco2")
		(25 "Edge.Cuts" user "Board Geometry/Outline")
		(27 "Margin" user)
		(31 "F.CrtYd" user "Package Geometry/Place Bound Top")
		(29 "B.CrtYd" user "Package Geometry/Place Bound Bottom")
		(35 "F.Fab" user "Ref Des/Assembly Top")
		(33 "B.Fab" user "Ref Des/Assembly Bottom")
	)
	(footprint ""
		(layer "F.Cu")
		(at 84.328 -76.581 90)
		(property "Reference" "TP1"
			(at 1.5875 -0.08763 90)
			(unlocked yes)
			(layer "F.SilkS")
			(effects
				(font
					(size 0.7874 0.5842)
					(thickness 0.1524)
				)
				(justify left)
			)
		)
		(property "Value" ""
			(at 0 0 90)
			(layer "F.Fab")
			(effects
				(font
					(size 1.27 1.27)
				)
			)
		)
		(property "Device Type" "TP_PIONT-TP010CT020B030_PTH-TPA"
			(at -1.341882 0.996696 90)
			(unlocked yes)
			(layer "F.Fab")
			(hide yes)
			(effects
				(font
					(size 0.7874 0.5842)
					(thickness 0.1524)
				)
				(justify left)
			)
		)
		(duplicate_pad_numbers_are_jumpers no)
		(fp_poly
			(pts
				(arc
					(start 0 0.889)
					(mid 0 -0.889)
					(end 0 0.889)
				)
			)
			(stroke
				(width 0)
				(type default)
			)
			(fill no)
			(layer "B.CrtYd")
		)
		(fp_poly
			(pts
				(arc
					(start 0 0.889)
					(mid 0 -0.889)
					(end 0 0.889)
				)
			)
			(stroke
				(width 0)
				(type default)
			)
			(fill no)
			(layer "F.CrtYd")
		)
		(pad "1" thru_hole circle
			(at 0 0 90)
			(size 0.508 0.508)
			(drill 0.254)
			(layers "*.Cu" "*.Mask")
			(remove_unused_layers no)
			(net "BNO080_EVN_SDA")
			(clearance 0.1016)
			(padstack
				(mode front_inner_back)
				(layer "Inner"
					(shape circle)
					(size 0.508 0.508)
					(clearance 0.1016)
				)
				(layer "B.Cu"
					(shape circle)
					(size 0.762 0.762)
					(clearance -0.0254)
				)
			)
		)
	)
	(footprint ""
		(layer "F.Cu")
		(at 119.761 -21.971)
		(property "Reference" "R474"
			(at -2.794 0.92837 0)
			(unlocked yes)
			(layer "F.SilkS")
			(effects
				(font
					(size 0.7874 0.5842)
					(thickness 0.1524)
				)
			)
		)
		(property "Value" "VAL*"
			(at 0.02032 2.13233 0)
			(unlocked yes)
			(layer "F.Fab")
			(hide yes)
			(effects
				(font
					(size 0.7874 0.5842)
					(thickness 0.1524)
				)
			)
		)
		(property "Tolerance" "TOL*"
			(at 0.044704 3.05435 0)
			(unlocked yes)
			(layer "Cmts.User")
			(hide yes)
			(effects
				(font
					(size 0.7874 0.5842)
					(thickness 0.1524)
				)
			)
		)
		(property "User Part Number" "PARTNUM*"
			(at 0.02032 4.024884 0)
			(unlocked yes)
			(layer "Cmts.User")
			(hide yes)
			(effects
				(font
					(size 0.7874 0.5842)
					(thickness 0.1524)
				)
			)
		)
		(property "Device Type" "RESISTOR-G155-11003-01,100KOHMA"
			(at 0.008382 1.210564 0)
			(unlocked yes)
			(layer "F.Fab")
			(hide yes)
			(effects
				(font
					(size 0.7874 0.5842)
					(thickness 0.1524)
				)
			)
		)
		(duplicate_pad_numbers_are_jumpers no)
		(fp_line
			(start -1.143 -0.5588)
			(end -1.143 0.5588)
			(stroke
				(width 0.1)
				(type default)
			)
			(layer "F.SilkS")
		)
		(fp_line
			(start -1.143 0.5588)
			(end 1.143 0.5588)
			(stroke
				(width 0.1)
				(type default)
			)
			(layer "F.SilkS")
		)
		(fp_line
			(start 1.143 -0.5588)
			(end -1.143 -0.5588)
			(stroke
				(width 0.1)
				(type default)
			)
			(layer "F.SilkS")
		)
		(fp_line
			(start 1.143 0.5588)
			(end 1.143 -0.5588)
			(stroke
				(width 0.1)
				(type default)
			)
			(layer "F.SilkS")
		)
		(fp_poly
			(pts
				(xy -1.143 0.5588) (xy 1.143 0.5588) (xy 1.143 -0.5588) (xy -1.143 -0.5588)
			)
			(stroke
				(width 0)
				(type default)
			)
			(fill no)
			(layer "F.CrtYd")
		)
		(fp_line
			(start -0.508 -0.3048)
			(end -0.508 0.3048)
			(stroke
				(width 0.1)
				(type default)
			)
			(layer "F.Fab")
		)
		(fp_line
			(start -0.508 0.3048)
			(end 0.508 0.3048)
			(stroke
				(width 0.1)
				(type default)
			)
			(layer "F.Fab")
		)
		(fp_line
			(start 0.508 -0.3048)
			(end -0.508 -0.3048)
			(stroke
				(width 0.1)
				(type default)
			)
			(layer "F.Fab")
		)
		(fp_line
			(start 0.508 0.3048)
			(end 0.508 -0.3048)
			(stroke
				(width 0.1)
				(type default)
			)
			(layer "F.Fab")
		)
		(pad "1" smd rect
			(at -0.5334 0)
			(size 0.7112 0.6096)
			(layers "F.Cu" "F.Mask" "F.Paste")
			(net "XP3R3V_FPGA")
		)
		(pad "2" smd rect
			(at 0.5334 0)
			(size 0.7112 0.6096)
			(layers "F.Cu" "F.Mask" "F.Paste")
			(net "FPGA_PCA9546_I2C_SDA")
		)
		(zone
			(layer "F.Cu")
			(hatch none 0.5)
			(connect_pads
				(clearance 0)
			)
			(min_thickness 0.25)
			(keepout
				(tracks allowed)
				(vias not_allowed)
				(pads allowed)
				(copperpour not_allowed)
				(footprints allowed)
			)
			(placement
				(enabled no)
				(sheetname "")
			)
			(fill
				(thermal_gap 0.5)
				(thermal_bridge_width 0.5)
				(island_removal_mode 0)
			)
			(polygon
				(pts
					(xy 119.6848 -21.6662) (xy 119.8372 -21.6662) (xy 119.8372 -22.2758) (xy 119.6848 -22.2758)
				)
			)
		)
		(zone
			(layer "F.Cu")
			(hatch none 0.5)
			(connect_pads
				(clearance 0)
			)
			(min_thickness 0.25)
			(keepout
				(tracks not_allowed)
				(vias allowed)
				(pads allowed)
				(copperpour not_allowed)
				(footprints allowed)
			)
			(placement
				(enabled no)
				(sheetname "")
			)
			(fill
				(thermal_gap 0.5)
				(thermal_bridge_width 0.5)
				(island_removal_mode 0)
			)
			(polygon
				(pts
					(xy 119.6848 -21.6662) (xy 119.8372 -21.6662) (xy 119.8372 -22.2758) (xy 119.6848 -22.2758)
				)
			)
		)
	)
)
